FILE_TYPE = MACRO_DRAWING;
SET COLOR_WIRE YELLOW;
SET COLOR_PROP ORANGE;
SET COLOR_DOT WHITE;
SET COLOR_ARC YELLOW;
SET COLOR_BODY GREEN;
SET COLOR_NOTE PURPLE;
SET PROP_DISPLAY VALUE;
SET PAGE_NUMBER P125;
FORCEADD OFFPAGE..1
(-6750 -50);
FORCEPROP 2 LAST $XR1 219 
J 0
(-7122 -50);
DISPLAY 0.638298 (-7122 -50);
PAINT MONO (-7122 -50);
FORCEPROP 2 LAST $XR0 216 
J 0
(-7002 -50);
DISPLAY 0.638298 (-7002 -50);
PAINT MONO (-7002 -50);
FORCEPROP 2 LAST CDS_LIB standard
J 0
(-6750 -50);
PAINT MONO (-6750 -50);
DISPLAY INVISIBLE (-6750 -50);
FORCEPROP 1 LAST OFFPAGE TRUE
J 0
(-6425 -175);
DISPLAY 0.872340 (-6425 -175);
PAINT GREEN (-6425 -175);
DISPLAY INVISIBLE (-6425 -175);
FORCEPROP 1 LAST COMMENT_BODY TRUE
J 0
(-6625 -150);
DISPLAY 0.872340 (-6625 -150);
PAINT GREEN (-6625 -150);
DISPLAY INVISIBLE (-6625 -150);
FORCEPROP 2 LAST PATH I1
J 0
(-6700 25);
DISPLAY 1.021277 (-6700 25);
DISPLAY INVISIBLE (-6700 25);
FORCEADD OFFPAGE..1
(-6750 775);
FORCEPROP 2 LAST $XR1 219 
J 0
(-7122 775);
DISPLAY 0.638298 (-7122 775);
PAINT MONO (-7122 775);
FORCEPROP 2 LAST $XR0 216 
J 0
(-7002 775);
DISPLAY 0.638298 (-7002 775);
PAINT MONO (-7002 775);
FORCEPROP 2 LAST CDS_LIB standard
J 0
(-6750 775);
PAINT MONO (-6750 775);
DISPLAY INVISIBLE (-6750 775);
FORCEPROP 1 LAST OFFPAGE TRUE
J 0
(-6425 650);
DISPLAY 0.872340 (-6425 650);
PAINT GREEN (-6425 650);
DISPLAY INVISIBLE (-6425 650);
FORCEPROP 1 LAST COMMENT_BODY TRUE
J 0
(-6625 675);
DISPLAY 0.872340 (-6625 675);
PAINT GREEN (-6625 675);
DISPLAY INVISIBLE (-6625 675);
FORCEPROP 2 LAST PATH I10
J 0
(-6700 850);
DISPLAY 1.021277 (-6700 850);
DISPLAY INVISIBLE (-6700 850);
FORCEADD OFFPAGE..1
(-6750 3275);
FORCEPROP 2 LAST $XR1 219 
J 0
(-7122 3275);
DISPLAY 0.638298 (-7122 3275);
PAINT MONO (-7122 3275);
FORCEPROP 2 LAST $XR0 216 
J 0
(-7002 3275);
DISPLAY 0.638298 (-7002 3275);
PAINT MONO (-7002 3275);
FORCEPROP 2 LAST CDS_LIB standard
J 0
(-6750 3275);
PAINT MONO (-6750 3275);
DISPLAY INVISIBLE (-6750 3275);
FORCEPROP 1 LAST OFFPAGE TRUE
J 0
(-6425 3150);
DISPLAY 0.872340 (-6425 3150);
PAINT GREEN (-6425 3150);
DISPLAY INVISIBLE (-6425 3150);
FORCEPROP 1 LAST COMMENT_BODY TRUE
J 0
(-6625 3175);
DISPLAY 0.872340 (-6625 3175);
PAINT GREEN (-6625 3175);
DISPLAY INVISIBLE (-6625 3175);
FORCEPROP 2 LAST PATH I11
J 0
(-6700 3350);
DISPLAY 1.021277 (-6700 3350);
DISPLAY INVISIBLE (-6700 3350);
FORCEADD Q_RES..1
(-5300 1600);
FORCEPROP 1 LAST PART_NUMBER CS00002JB13
J 0
(-5400 1675);
DISPLAY 0.510638 (-5400 1675);
DISPLAY INVISIBLE (-5400 1675);
FORCEPROP 1 LAST MATERIAL CHIP
J 0
(-5400 1725);
DISPLAY 0.510638 (-5400 1725);
FORCEPROP 1 LAST TOLERANCE 5%
J 0
(-5125 1600);
DISPLAY 0.638298 (-5125 1600);
FORCEPROP 1 LAST VALUE 0
J 2
(-5150 1600);
DISPLAY 0.638298 (-5150 1600);
FORCEPROP 1 LAST PACK_TYPE 0402LF
J 0
(-5050 1600);
DISPLAY 0.638298 (-5050 1600);
FORCEPROP 1 LAST WATTAGE 1/16W
J 2
(-5175 1725);
DISPLAY 0.510638 (-5175 1725);
FORCEPROP 1 LAST $LOCATION R126
J 0
(-5500 1600);
DISPLAY 0.638298 (-5500 1600);
FORCEPROP 1 LASTPIN (-5400 1600) $PN 1
J 0
(-5388 1612);
DISPLAY 0.787234 (-5388 1612);
FORCEPROP 1 LASTPIN (-5200 1600) $PN 2
J 0
(-5238 1612);
DISPLAY 0.787234 (-5238 1612);
FORCEPROP 2 LAST CDS_LIB pure_quanta
J 0
(-5300 1600);
PAINT MONO (-5300 1600);
DISPLAY INVISIBLE (-5300 1600);
FORCEPROP 1 LAST PATH I13
J 0
(-5350 1750);
DISPLAY 0.978723 (-5350 1750);
PAINT WHITE (-5350 1750);
DISPLAY INVISIBLE (-5350 1750);
FORCEPROP 2 LAST CDS_LOCATION R126
J 0
(-5350 1800);
DISPLAY 1.021277 (-5350 1800);
DISPLAY INVISIBLE (-5350 1800);
FORCEPROP 2 LAST $SEC 1
J 0
(-5350 1800);
DISPLAY 0.680851 (-5350 1800);
PAINT MONO (-5350 1800);
DISPLAY INVISIBLE (-5350 1800);
FORCEPROP 2 LAST CDS_SEC 1
J 0
(-5350 1800);
DISPLAY 1.021277 (-5350 1800);
DISPLAY INVISIBLE (-5350 1800);
FORCEADD Q_RES..1
(-5300 2450);
FORCEPROP 1 LAST PART_NUMBER CS00002JB13
J 0
(-5400 2525);
DISPLAY 0.510638 (-5400 2525);
DISPLAY INVISIBLE (-5400 2525);
FORCEPROP 1 LAST PACK_TYPE 0402LF
J 0
(-5050 2450);
DISPLAY 0.638298 (-5050 2450);
FORCEPROP 1 LAST MATERIAL CHIP
J 0
(-5400 2575);
DISPLAY 0.510638 (-5400 2575);
FORCEPROP 1 LAST WATTAGE 1/16W
J 2
(-5175 2575);
DISPLAY 0.510638 (-5175 2575);
FORCEPROP 1 LAST TOLERANCE 5%
J 0
(-5125 2450);
DISPLAY 0.638298 (-5125 2450);
FORCEPROP 1 LAST VALUE 0
J 2
(-5150 2450);
DISPLAY 0.638298 (-5150 2450);
FORCEPROP 1 LAST $LOCATION R124
J 0
(-5500 2450);
DISPLAY 0.638298 (-5500 2450);
FORCEPROP 1 LASTPIN (-5400 2450) $PN 1
J 0
(-5388 2462);
DISPLAY 0.787234 (-5388 2462);
FORCEPROP 1 LASTPIN (-5200 2450) $PN 2
J 0
(-5238 2462);
DISPLAY 0.787234 (-5238 2462);
FORCEPROP 2 LAST CDS_LIB pure_quanta
J 0
(-5300 2450);
PAINT MONO (-5300 2450);
DISPLAY INVISIBLE (-5300 2450);
FORCEPROP 1 LAST PATH I15
J 0
(-5350 2600);
DISPLAY 0.978723 (-5350 2600);
PAINT WHITE (-5350 2600);
DISPLAY INVISIBLE (-5350 2600);
FORCEPROP 2 LAST CDS_LOCATION R124
J 0
(-5350 2650);
DISPLAY 1.021277 (-5350 2650);
DISPLAY INVISIBLE (-5350 2650);
FORCEPROP 2 LAST $SEC 1
J 0
(-5350 2650);
DISPLAY 0.680851 (-5350 2650);
PAINT MONO (-5350 2650);
DISPLAY INVISIBLE (-5350 2650);
FORCEPROP 2 LAST CDS_SEC 1
J 0
(-5350 2650);
DISPLAY 1.021277 (-5350 2650);
DISPLAY INVISIBLE (-5350 2650);
FORCEADD Q_RES..1
(-5300 3275);
FORCEPROP 1 LAST PART_NUMBER CS00002JB13
J 0
(-5400 3350);
DISPLAY 0.510638 (-5400 3350);
DISPLAY INVISIBLE (-5400 3350);
FORCEPROP 1 LAST WATTAGE 1/16W
J 2
(-5175 3400);
DISPLAY 0.510638 (-5175 3400);
FORCEPROP 1 LAST VALUE 0
J 2
(-5150 3275);
DISPLAY 0.638298 (-5150 3275);
FORCEPROP 1 LAST TOLERANCE 5%
J 0
(-5125 3275);
DISPLAY 0.638298 (-5125 3275);
FORCEPROP 1 LAST PACK_TYPE 0402LF
J 0
(-5050 3275);
DISPLAY 0.638298 (-5050 3275);
FORCEPROP 1 LAST MATERIAL CHIP
J 0
(-5400 3400);
DISPLAY 0.510638 (-5400 3400);
FORCEPROP 1 LAST $LOCATION R122
J 0
(-5500 3275);
DISPLAY 0.638298 (-5500 3275);
FORCEPROP 1 LASTPIN (-5400 3275) $PN 1
J 0
(-5388 3287);
DISPLAY 0.787234 (-5388 3287);
FORCEPROP 1 LASTPIN (-5200 3275) $PN 2
J 0
(-5238 3287);
DISPLAY 0.787234 (-5238 3287);
FORCEPROP 2 LAST CDS_LIB pure_quanta
J 0
(-5300 3275);
PAINT MONO (-5300 3275);
DISPLAY INVISIBLE (-5300 3275);
FORCEPROP 1 LAST PATH I17
J 0
(-5350 3425);
DISPLAY 0.978723 (-5350 3425);
PAINT WHITE (-5350 3425);
DISPLAY INVISIBLE (-5350 3425);
FORCEPROP 2 LAST CDS_LOCATION R122
J 0
(-5350 3475);
DISPLAY 1.021277 (-5350 3475);
DISPLAY INVISIBLE (-5350 3475);
FORCEPROP 2 LAST $SEC 1
J 0
(-5350 3475);
DISPLAY 0.680851 (-5350 3475);
PAINT MONO (-5350 3475);
DISPLAY INVISIBLE (-5350 3475);
FORCEPROP 2 LAST CDS_SEC 1
J 0
(-5350 3475);
DISPLAY 1.021277 (-5350 3475);
DISPLAY INVISIBLE (-5350 3475);
FORCEADD OFFPAGE..1
(-6750 -900);
FORCEPROP 2 LAST $XR1 219 
J 0
(-7122 -900);
DISPLAY 0.638298 (-7122 -900);
PAINT MONO (-7122 -900);
FORCEPROP 2 LAST $XR0 216 
J 0
(-7002 -900);
DISPLAY 0.638298 (-7002 -900);
PAINT MONO (-7002 -900);
FORCEPROP 2 LAST CDS_LIB standard
J 0
(-6750 -900);
PAINT MONO (-6750 -900);
DISPLAY INVISIBLE (-6750 -900);
FORCEPROP 1 LAST OFFPAGE TRUE
J 0
(-6425 -1025);
DISPLAY 0.872340 (-6425 -1025);
PAINT GREEN (-6425 -1025);
DISPLAY INVISIBLE (-6425 -1025);
FORCEPROP 1 LAST COMMENT_BODY TRUE
J 0
(-6625 -1000);
DISPLAY 0.872340 (-6625 -1000);
PAINT GREEN (-6625 -1000);
DISPLAY INVISIBLE (-6625 -1000);
FORCEPROP 2 LAST PATH I2
J 0
(-6700 -825);
DISPLAY 1.021277 (-6700 -825);
DISPLAY INVISIBLE (-6700 -825);
FORCEADD Q_RES..1
(-1125 -725);
FORCEPROP 1 LAST PART_NUMBER CS11002FB07
J 0
(-1250 -675);
DISPLAY 0.404255 (-1250 -675);
DISPLAY INVISIBLE (-1250 -675);
FORCEPROP 1 LAST VALUE 100
J 2
(-950 -725);
DISPLAY 0.510638 (-950 -725);
FORCEPROP 1 LAST WATTAGE 1/16W
J 2
(-975 -650);
DISPLAY 0.404255 (-975 -650);
FORCEPROP 1 LAST PACK_TYPE 0402LF
J 0
(-1250 -650);
DISPLAY 0.404255 (-1250 -650);
FORCEPROP 1 LAST MATERIAL CHIP
J 0
(-850 -725);
DISPLAY 0.510638 (-850 -725);
FORCEPROP 1 LAST TOLERANCE 1%
J 0
(-925 -725);
DISPLAY 0.510638 (-925 -725);
FORCEPROP 1 LAST $LOCATION R157
J 0
(-1325 -725);
DISPLAY 0.638298 (-1325 -725);
FORCEPROP 1 LASTPIN (-1225 -725) $PN 1
J 0
(-1213 -713);
DISPLAY 0.787234 (-1213 -713);
FORCEPROP 1 LASTPIN (-1025 -725) $PN 2
J 0
(-1063 -713);
DISPLAY 0.787234 (-1063 -713);
FORCEPROP 2 LAST CDS_LIB pure_quanta
J 0
(-1125 -725);
PAINT MONO (-1125 -725);
DISPLAY INVISIBLE (-1125 -725);
FORCEPROP 1 LAST PATH I24
J 0
(-1175 -575);
DISPLAY 0.978723 (-1175 -575);
PAINT WHITE (-1175 -575);
DISPLAY INVISIBLE (-1175 -575);
FORCEPROP 2 LAST CDS_LOCATION R157
J 0
(-1175 -525);
DISPLAY 1.021277 (-1175 -525);
DISPLAY INVISIBLE (-1175 -525);
FORCEPROP 2 LAST $SEC 1
J 0
(-1175 -525);
DISPLAY 0.680851 (-1175 -525);
PAINT MONO (-1175 -525);
DISPLAY INVISIBLE (-1175 -525);
FORCEPROP 2 LAST CDS_SEC 1
J 0
(-1175 -525);
DISPLAY 1.021277 (-1175 -525);
DISPLAY INVISIBLE (-1175 -525);
FORCEADD Q_RES..1
(-1125 125);
FORCEPROP 1 LAST PART_NUMBER CS11002FB07
J 0
(-1250 175);
DISPLAY 0.404255 (-1250 175);
DISPLAY INVISIBLE (-1250 175);
FORCEPROP 1 LAST PACK_TYPE 0402LF
J 0
(-1250 200);
DISPLAY 0.404255 (-1250 200);
FORCEPROP 1 LAST MATERIAL CHIP
J 0
(-850 125);
DISPLAY 0.510638 (-850 125);
FORCEPROP 1 LAST WATTAGE 1/16W
J 2
(-975 200);
DISPLAY 0.404255 (-975 200);
FORCEPROP 1 LAST VALUE 100
J 2
(-950 125);
DISPLAY 0.510638 (-950 125);
FORCEPROP 1 LAST TOLERANCE 1%
J 0
(-925 125);
DISPLAY 0.510638 (-925 125);
FORCEPROP 1 LAST $LOCATION R155
J 0
(-1325 125);
DISPLAY 0.638298 (-1325 125);
FORCEPROP 1 LASTPIN (-1225 125) $PN 1
J 0
(-1213 137);
DISPLAY 0.787234 (-1213 137);
FORCEPROP 1 LASTPIN (-1025 125) $PN 2
J 0
(-1063 137);
DISPLAY 0.787234 (-1063 137);
FORCEPROP 2 LAST CDS_LIB pure_quanta
J 0
(-1125 125);
PAINT MONO (-1125 125);
DISPLAY INVISIBLE (-1125 125);
FORCEPROP 1 LAST PATH I26
J 0
(-1175 275);
DISPLAY 0.978723 (-1175 275);
PAINT WHITE (-1175 275);
DISPLAY INVISIBLE (-1175 275);
FORCEPROP 2 LAST CDS_LOCATION R155
J 0
(-1175 325);
DISPLAY 1.021277 (-1175 325);
DISPLAY INVISIBLE (-1175 325);
FORCEPROP 2 LAST $SEC 1
J 0
(-1175 325);
DISPLAY 0.680851 (-1175 325);
PAINT MONO (-1175 325);
DISPLAY INVISIBLE (-1175 325);
FORCEPROP 2 LAST CDS_SEC 1
J 0
(-1175 325);
DISPLAY 1.021277 (-1175 325);
DISPLAY INVISIBLE (-1175 325);
FORCEADD UNIVERSAL_POWER..1
(-525 -625);
FORCEPROP 3 LASTPIN (-525 -675) SIG_NAME PVNN_TERM_CPU1\g
J 0
(-515 -665);
DISPLAY 0.659574 (-515 -665);
PAINT MONO (-515 -665);
DISPLAY INVISIBLE (-515 -665);
FORCEPROP 1 LAST HDL_POWER PVNN_TERM_CPU1
J 1
(-525 -575);
DISPLAY 0.872340 (-525 -575);
PAINT GREEN (-525 -575);
FORCEPROP 2 LAST CDS_LIB logical_power
J 0
(-525 -625);
PAINT MONO (-525 -625);
DISPLAY INVISIBLE (-525 -625);
FORCEPROP 1 LAST PATH I27
J 0
(-475 -600);
DISPLAY 0.872340 (-475 -600);
PAINT AQUA (-475 -600);
DISPLAY INVISIBLE (-475 -600);
FORCEADD OFFPAGE..2
(-125 -900);
FORCEPROP 2 LAST $XR0 45 
J 0
(64 -900);
DISPLAY 0.638298 (64 -900);
PAINT MONO (64 -900);
FORCEPROP 2 LAST CDS_LIB standard
J 0
(-125 -900);
DISPLAY INVISIBLE (-125 -900);
FORCEPROP 1 LAST OFFPAGE TRUE
J 0
(200 -1025);
DISPLAY 0.872340 (200 -1025);
PAINT GREEN (200 -1025);
DISPLAY INVISIBLE (200 -1025);
FORCEPROP 1 LAST COMMENT_BODY TRUE
J 0
(-170 -995);
DISPLAY 0.872340 (-170 -995);
PAINT GREEN (-170 -995);
DISPLAY INVISIBLE (-170 -995);
FORCEPROP 2 LAST PATH I28
J 0
(75 -850);
DISPLAY 1.021277 (75 -850);
DISPLAY INVISIBLE (75 -850);
FORCEADD UNIVERSAL_POWER..1
(-525 225);
FORCEPROP 3 LASTPIN (-525 175) SIG_NAME PVNN_TERM_CPU1\g
J 0
(-515 185);
DISPLAY 0.659574 (-515 185);
PAINT MONO (-515 185);
DISPLAY INVISIBLE (-515 185);
FORCEPROP 1 LAST HDL_POWER PVNN_TERM_CPU1
J 1
(-525 275);
DISPLAY 0.872340 (-525 275);
PAINT GREEN (-525 275);
FORCEPROP 2 LAST CDS_LIB logical_power
J 0
(-525 225);
PAINT MONO (-525 225);
DISPLAY INVISIBLE (-525 225);
FORCEPROP 1 LAST PATH I29
J 0
(-475 250);
DISPLAY 0.872340 (-475 250);
PAINT AQUA (-475 250);
DISPLAY INVISIBLE (-475 250);
FORCEADD Q_RES..1
(-5300 -900);
FORCEPROP 1 LAST PART_NUMBER CS00002JB13
J 0
(-5350 -850);
DISPLAY 0.404255 (-5350 -850);
DISPLAY INVISIBLE (-5350 -850);
FORCEPROP 1 LAST MATERIAL CHIP
J 0
(-5350 -825);
DISPLAY 0.404255 (-5350 -825);
FORCEPROP 1 LAST VALUE 0
J 2
(-5150 -900);
DISPLAY 0.510638 (-5150 -900);
FORCEPROP 1 LAST TOLERANCE 5%
J 0
(-5125 -900);
DISPLAY 0.510638 (-5125 -900);
FORCEPROP 1 LAST PACK_TYPE 0402LF
J 0
(-5050 -900);
DISPLAY 0.510638 (-5050 -900);
FORCEPROP 1 LAST WATTAGE 1/16W
J 2
(-5125 -825);
DISPLAY 0.404255 (-5125 -825);
FORCEPROP 1 LAST $LOCATION R132
J 0
(-5500 -900);
DISPLAY 0.638298 (-5500 -900);
FORCEPROP 1 LASTPIN (-5400 -900) $PN 1
J 0
(-5388 -888);
DISPLAY 0.787234 (-5388 -888);
FORCEPROP 1 LASTPIN (-5200 -900) $PN 2
J 0
(-5238 -888);
DISPLAY 0.787234 (-5238 -888);
FORCEPROP 2 LAST CDS_LIB pure_quanta
J 0
(-5300 -900);
PAINT MONO (-5300 -900);
DISPLAY INVISIBLE (-5300 -900);
FORCEPROP 1 LAST PATH I3
J 0
(-5350 -750);
DISPLAY 0.978723 (-5350 -750);
PAINT WHITE (-5350 -750);
DISPLAY INVISIBLE (-5350 -750);
FORCEPROP 2 LAST CDS_LOCATION R132
J 0
(-5350 -700);
DISPLAY 1.021277 (-5350 -700);
DISPLAY INVISIBLE (-5350 -700);
FORCEPROP 2 LAST $SEC 1
J 0
(-5350 -700);
DISPLAY 0.680851 (-5350 -700);
PAINT MONO (-5350 -700);
DISPLAY INVISIBLE (-5350 -700);
FORCEPROP 2 LAST CDS_SEC 1
J 0
(-5350 -700);
DISPLAY 1.021277 (-5350 -700);
DISPLAY INVISIBLE (-5350 -700);
FORCEADD OFFPAGE..2
(-125 -50);
FORCEPROP 2 LAST $XR0 45 
J 0
(64 -50);
DISPLAY 0.638298 (64 -50);
PAINT MONO (64 -50);
FORCEPROP 2 LAST CDS_LIB standard
J 0
(-125 -50);
DISPLAY INVISIBLE (-125 -50);
FORCEPROP 1 LAST OFFPAGE TRUE
J 0
(200 -175);
DISPLAY 0.872340 (200 -175);
PAINT GREEN (200 -175);
DISPLAY INVISIBLE (200 -175);
FORCEPROP 1 LAST COMMENT_BODY TRUE
J 0
(-170 -145);
DISPLAY 0.872340 (-170 -145);
PAINT GREEN (-170 -145);
DISPLAY INVISIBLE (-170 -145);
FORCEPROP 2 LAST PATH I30
J 0
(75 0);
DISPLAY 1.021277 (75 0);
DISPLAY INVISIBLE (75 0);
FORCEADD Q_RES..1
(-5300 -50);
FORCEPROP 1 LAST PART_NUMBER CS00002JB13
J 0
(-5350 0);
DISPLAY 0.404255 (-5350 0);
DISPLAY INVISIBLE (-5350 0);
FORCEPROP 1 LAST MATERIAL CHIP
J 0
(-5350 25);
DISPLAY 0.404255 (-5350 25);
FORCEPROP 1 LAST WATTAGE 1/16W
J 2
(-5125 25);
DISPLAY 0.404255 (-5125 25);
FORCEPROP 1 LAST VALUE 0
J 2
(-5150 -50);
DISPLAY 0.510638 (-5150 -50);
FORCEPROP 1 LAST TOLERANCE 5%
J 0
(-5125 -50);
DISPLAY 0.510638 (-5125 -50);
FORCEPROP 1 LAST PACK_TYPE 0402LF
J 0
(-5050 -50);
DISPLAY 0.510638 (-5050 -50);
FORCEPROP 1 LAST $LOCATION R130
J 0
(-5500 -50);
DISPLAY 0.638298 (-5500 -50);
FORCEPROP 1 LASTPIN (-5400 -50) $PN 1
J 0
(-5388 -38);
DISPLAY 0.787234 (-5388 -38);
FORCEPROP 1 LASTPIN (-5200 -50) $PN 2
J 0
(-5238 -38);
DISPLAY 0.787234 (-5238 -38);
FORCEPROP 2 LAST CDS_LIB pure_quanta
J 0
(-5300 -50);
PAINT MONO (-5300 -50);
DISPLAY INVISIBLE (-5300 -50);
FORCEPROP 1 LAST PATH I5
J 0
(-5350 100);
DISPLAY 0.978723 (-5350 100);
PAINT WHITE (-5350 100);
DISPLAY INVISIBLE (-5350 100);
FORCEPROP 2 LAST CDS_LOCATION R130
J 0
(-5350 150);
DISPLAY 1.021277 (-5350 150);
DISPLAY INVISIBLE (-5350 150);
FORCEPROP 2 LAST $SEC 1
J 0
(-5350 150);
DISPLAY 0.680851 (-5350 150);
PAINT MONO (-5350 150);
DISPLAY INVISIBLE (-5350 150);
FORCEPROP 2 LAST CDS_SEC 1
J 0
(-5350 150);
DISPLAY 1.021277 (-5350 150);
DISPLAY INVISIBLE (-5350 150);
FORCEADD Q_RES..1
(-1100 950);
FORCEPROP 1 LAST PART_NUMBER CS11002FB07
J 0
(-1225 1000);
DISPLAY 0.404255 (-1225 1000);
DISPLAY INVISIBLE (-1225 1000);
FORCEPROP 1 LAST MATERIAL CHIP
J 0
(-825 950);
DISPLAY 0.510638 (-825 950);
FORCEPROP 1 LAST PACK_TYPE 0402LF
J 0
(-1225 1025);
DISPLAY 0.404255 (-1225 1025);
FORCEPROP 1 LAST VALUE 100
J 2
(-925 950);
DISPLAY 0.510638 (-925 950);
FORCEPROP 1 LAST WATTAGE 1/16W
J 2
(-950 1025);
DISPLAY 0.404255 (-950 1025);
FORCEPROP 1 LAST TOLERANCE 1%
J 0
(-900 950);
DISPLAY 0.510638 (-900 950);
FORCEPROP 1 LAST $LOCATION R153
J 0
(-1300 950);
DISPLAY 0.638298 (-1300 950);
FORCEPROP 1 LASTPIN (-1200 950) $PN 1
J 0
(-1188 962);
DISPLAY 0.787234 (-1188 962);
FORCEPROP 1 LASTPIN (-1000 950) $PN 2
J 0
(-1038 962);
DISPLAY 0.787234 (-1038 962);
FORCEPROP 2 LAST CDS_LIB pure_quanta
J 0
(-1100 950);
PAINT MONO (-1100 950);
DISPLAY INVISIBLE (-1100 950);
FORCEPROP 1 LAST PATH I56
J 0
(-1150 1100);
DISPLAY 0.978723 (-1150 1100);
PAINT WHITE (-1150 1100);
DISPLAY INVISIBLE (-1150 1100);
FORCEPROP 2 LAST CDS_LOCATION R153
J 0
(-1150 1150);
DISPLAY 1.021277 (-1150 1150);
DISPLAY INVISIBLE (-1150 1150);
FORCEPROP 2 LAST $SEC 1
J 0
(-1150 1150);
DISPLAY 0.680851 (-1150 1150);
PAINT MONO (-1150 1150);
DISPLAY INVISIBLE (-1150 1150);
FORCEPROP 2 LAST CDS_SEC 1
J 0
(-1150 1150);
DISPLAY 1.021277 (-1150 1150);
DISPLAY INVISIBLE (-1150 1150);
FORCEADD UNIVERSAL_POWER..1
(-500 1050);
FORCEPROP 3 LASTPIN (-500 1000) SIG_NAME PVCCD_HV_CPU1\g
J 0
(-490 1010);
DISPLAY 0.659574 (-490 1010);
PAINT MONO (-490 1010);
DISPLAY INVISIBLE (-490 1010);
FORCEPROP 1 LAST HDL_POWER PVCCD_HV_CPU1
J 1
(-500 1100);
DISPLAY 0.872340 (-500 1100);
PAINT GREEN (-500 1100);
FORCEPROP 2 LAST CDS_LIB logical_power
J 0
(-500 1050);
PAINT MONO (-500 1050);
DISPLAY INVISIBLE (-500 1050);
FORCEPROP 1 LAST PATH I57
J 0
(-450 1075);
DISPLAY 0.872340 (-450 1075);
PAINT AQUA (-450 1075);
DISPLAY INVISIBLE (-450 1075);
FORCEADD Q_RES..1
(-1100 1775);
FORCEPROP 1 LAST PART_NUMBER CS11002FB07
J 0
(-1225 1825);
DISPLAY 0.404255 (-1225 1825);
DISPLAY INVISIBLE (-1225 1825);
FORCEPROP 1 LAST MATERIAL CHIP
J 0
(-825 1775);
DISPLAY 0.510638 (-825 1775);
FORCEPROP 1 LAST VALUE 100
J 2
(-925 1775);
DISPLAY 0.510638 (-925 1775);
FORCEPROP 1 LAST PACK_TYPE 0402LF
J 0
(-1225 1850);
DISPLAY 0.404255 (-1225 1850);
FORCEPROP 1 LAST WATTAGE 1/16W
J 2
(-950 1850);
DISPLAY 0.404255 (-950 1850);
FORCEPROP 1 LAST TOLERANCE 1%
J 0
(-900 1775);
DISPLAY 0.510638 (-900 1775);
FORCEPROP 1 LAST $LOCATION R151
J 0
(-1300 1775);
DISPLAY 0.638298 (-1300 1775);
FORCEPROP 1 LASTPIN (-1200 1775) $PN 1
J 0
(-1188 1787);
DISPLAY 0.787234 (-1188 1787);
FORCEPROP 1 LASTPIN (-1000 1775) $PN 2
J 0
(-1038 1787);
DISPLAY 0.787234 (-1038 1787);
FORCEPROP 2 LAST CDS_LIB pure_quanta
J 0
(-1100 1775);
PAINT MONO (-1100 1775);
DISPLAY INVISIBLE (-1100 1775);
FORCEPROP 1 LAST PATH I58
J 0
(-1150 1925);
DISPLAY 0.978723 (-1150 1925);
PAINT WHITE (-1150 1925);
DISPLAY INVISIBLE (-1150 1925);
FORCEPROP 2 LAST CDS_LOCATION R151
J 0
(-1150 1975);
DISPLAY 1.021277 (-1150 1975);
DISPLAY INVISIBLE (-1150 1975);
FORCEPROP 2 LAST $SEC 1
J 0
(-1150 1975);
DISPLAY 0.680851 (-1150 1975);
PAINT MONO (-1150 1975);
DISPLAY INVISIBLE (-1150 1975);
FORCEPROP 2 LAST CDS_SEC 1
J 0
(-1150 1975);
DISPLAY 1.021277 (-1150 1975);
DISPLAY INVISIBLE (-1150 1975);
FORCEADD UNIVERSAL_POWER..1
(-500 1875);
FORCEPROP 3 LASTPIN (-500 1825) SIG_NAME PVCCD_HV_CPU1\g
J 0
(-490 1835);
DISPLAY 0.659574 (-490 1835);
PAINT MONO (-490 1835);
DISPLAY INVISIBLE (-490 1835);
FORCEPROP 1 LAST HDL_POWER PVCCD_HV_CPU1
J 1
(-500 1925);
DISPLAY 0.872340 (-500 1925);
PAINT GREEN (-500 1925);
FORCEPROP 2 LAST CDS_LIB logical_power
J 0
(-500 1875);
PAINT MONO (-500 1875);
DISPLAY INVISIBLE (-500 1875);
FORCEPROP 1 LAST PATH I59
J 0
(-450 1900);
DISPLAY 0.872340 (-450 1900);
PAINT AQUA (-450 1900);
DISPLAY INVISIBLE (-450 1900);
FORCEADD Q_RES..1
(-1100 2625);
FORCEPROP 1 LAST PART_NUMBER CS11002FB07
J 0
(-1225 2675);
DISPLAY 0.404255 (-1225 2675);
DISPLAY INVISIBLE (-1225 2675);
FORCEPROP 1 LAST MATERIAL CHIP
J 0
(-825 2625);
DISPLAY 0.510638 (-825 2625);
FORCEPROP 1 LAST TOLERANCE 1%
J 0
(-900 2625);
DISPLAY 0.510638 (-900 2625);
FORCEPROP 1 LAST PACK_TYPE 0402LF
J 0
(-1225 2700);
DISPLAY 0.404255 (-1225 2700);
FORCEPROP 1 LAST WATTAGE 1/16W
J 2
(-950 2700);
DISPLAY 0.404255 (-950 2700);
FORCEPROP 1 LAST VALUE 100
J 2
(-925 2625);
DISPLAY 0.510638 (-925 2625);
FORCEPROP 1 LAST $LOCATION R137
J 0
(-1300 2625);
DISPLAY 0.638298 (-1300 2625);
FORCEPROP 1 LASTPIN (-1200 2625) $PN 1
J 0
(-1188 2637);
DISPLAY 0.787234 (-1188 2637);
FORCEPROP 1 LASTPIN (-1000 2625) $PN 2
J 0
(-1038 2637);
DISPLAY 0.787234 (-1038 2637);
FORCEPROP 2 LAST CDS_LIB pure_quanta
J 0
(-1100 2625);
PAINT MONO (-1100 2625);
DISPLAY INVISIBLE (-1100 2625);
FORCEPROP 1 LAST PATH I60
J 0
(-1150 2775);
DISPLAY 0.978723 (-1150 2775);
PAINT WHITE (-1150 2775);
DISPLAY INVISIBLE (-1150 2775);
FORCEPROP 2 LAST CDS_LOCATION R137
J 0
(-1150 2825);
DISPLAY 1.021277 (-1150 2825);
DISPLAY INVISIBLE (-1150 2825);
FORCEPROP 2 LAST $SEC 1
J 0
(-1150 2825);
DISPLAY 0.680851 (-1150 2825);
PAINT MONO (-1150 2825);
DISPLAY INVISIBLE (-1150 2825);
FORCEPROP 2 LAST CDS_SEC 1
J 0
(-1150 2825);
DISPLAY 1.021277 (-1150 2825);
DISPLAY INVISIBLE (-1150 2825);
FORCEADD UNIVERSAL_POWER..1
(-500 2725);
FORCEPROP 3 LASTPIN (-500 2675) SIG_NAME PVCCD_HV_CPU1\g
J 0
(-490 2685);
DISPLAY 0.659574 (-490 2685);
PAINT MONO (-490 2685);
DISPLAY INVISIBLE (-490 2685);
FORCEPROP 1 LAST HDL_POWER PVCCD_HV_CPU1
J 1
(-500 2775);
DISPLAY 0.872340 (-500 2775);
PAINT GREEN (-500 2775);
FORCEPROP 2 LAST CDS_LIB logical_power
J 0
(-500 2725);
PAINT MONO (-500 2725);
DISPLAY INVISIBLE (-500 2725);
FORCEPROP 1 LAST PATH I61
J 0
(-450 2750);
DISPLAY 0.872340 (-450 2750);
PAINT AQUA (-450 2750);
DISPLAY INVISIBLE (-450 2750);
FORCEADD Q_RES..1
(-1100 3450);
FORCEPROP 1 LAST PART_NUMBER CS11002FB07
J 0
(-1225 3500);
DISPLAY 0.404255 (-1225 3500);
DISPLAY INVISIBLE (-1225 3500);
FORCEPROP 1 LAST MATERIAL CHIP
J 0
(-825 3450);
DISPLAY 0.510638 (-825 3450);
FORCEPROP 1 LAST TOLERANCE 1%
J 0
(-900 3450);
DISPLAY 0.510638 (-900 3450);
FORCEPROP 1 LAST WATTAGE 1/16W
J 2
(-950 3525);
DISPLAY 0.404255 (-950 3525);
FORCEPROP 1 LAST VALUE 100
J 2
(-925 3450);
DISPLAY 0.510638 (-925 3450);
FORCEPROP 1 LAST PACK_TYPE 0402LF
J 0
(-1225 3525);
DISPLAY 0.404255 (-1225 3525);
FORCEPROP 1 LAST $LOCATION R135
J 0
(-1300 3450);
DISPLAY 0.638298 (-1300 3450);
FORCEPROP 1 LASTPIN (-1200 3450) $PN 1
J 0
(-1188 3462);
DISPLAY 0.787234 (-1188 3462);
FORCEPROP 1 LASTPIN (-1000 3450) $PN 2
J 0
(-1038 3462);
DISPLAY 0.787234 (-1038 3462);
FORCEPROP 2 LAST CDS_LIB pure_quanta
J 0
(-1100 3450);
PAINT MONO (-1100 3450);
DISPLAY INVISIBLE (-1100 3450);
FORCEPROP 1 LAST PATH I62
J 0
(-1150 3600);
DISPLAY 0.978723 (-1150 3600);
PAINT WHITE (-1150 3600);
DISPLAY INVISIBLE (-1150 3600);
FORCEPROP 2 LAST CDS_LOCATION R135
J 0
(-1150 3650);
DISPLAY 1.021277 (-1150 3650);
DISPLAY INVISIBLE (-1150 3650);
FORCEPROP 2 LAST $SEC 1
J 0
(-1150 3650);
DISPLAY 0.680851 (-1150 3650);
PAINT MONO (-1150 3650);
DISPLAY INVISIBLE (-1150 3650);
FORCEPROP 2 LAST CDS_SEC 1
J 0
(-1150 3650);
DISPLAY 1.021277 (-1150 3650);
DISPLAY INVISIBLE (-1150 3650);
FORCEADD UNIVERSAL_POWER..1
(-500 3550);
FORCEPROP 3 LASTPIN (-500 3500) SIG_NAME PVCCD_HV_CPU1\g
J 0
(-490 3510);
DISPLAY 0.659574 (-490 3510);
PAINT MONO (-490 3510);
DISPLAY INVISIBLE (-490 3510);
FORCEPROP 1 LAST HDL_POWER PVCCD_HV_CPU1
J 1
(-500 3600);
DISPLAY 0.872340 (-500 3600);
PAINT GREEN (-500 3600);
FORCEPROP 2 LAST CDS_LIB logical_power
J 0
(-500 3550);
PAINT MONO (-500 3550);
DISPLAY INVISIBLE (-500 3550);
FORCEPROP 1 LAST PATH I63
J 0
(-450 3575);
DISPLAY 0.872340 (-450 3575);
PAINT AQUA (-450 3575);
DISPLAY INVISIBLE (-450 3575);
FORCEADD Q_RES..1
(-1125 -50);
FORCEPROP 1 LAST PART_NUMBER CS11002FB07
J 0
(-1250 0);
DISPLAY 0.404255 (-1250 0);
DISPLAY INVISIBLE (-1250 0);
FORCEPROP 1 LAST TOLERANCE 1%
J 0
(-925 -50);
DISPLAY 0.510638 (-925 -50);
FORCEPROP 1 LAST PACK_TYPE 0402LF
J 0
(-1275 25);
DISPLAY 0.404255 (-1275 25);
FORCEPROP 1 LAST VALUE 100
J 2
(-950 -50);
DISPLAY 0.510638 (-950 -50);
FORCEPROP 1 LAST WATTAGE 1/16W
J 2
(-975 25);
DISPLAY 0.404255 (-975 25);
FORCEPROP 1 LAST MATERIAL CHIP
J 0
(-850 -50);
DISPLAY 0.510638 (-850 -50);
FORCEPROP 1 LAST LOCATION R156
J 0
(-1325 -50);
DISPLAY 0.638298 (-1325 -50);
FORCEPROP 1 LASTPIN (-1225 -50) $PN 1
J 0
(-1213 -38);
DISPLAY 0.787234 (-1213 -38);
PAINT MONO (-1213 -38);
FORCEPROP 1 LASTPIN (-1025 -50) $PN 2
J 0
(-1063 -38);
DISPLAY 0.787234 (-1063 -38);
PAINT MONO (-1063 -38);
FORCEPROP 2 LAST CDS_LIB pure_quanta
J 0
(-1125 -50);
DISPLAY INVISIBLE (-1125 -50);
FORCEPROP 1 LAST PATH I64
J 0
(-1175 100);
DISPLAY 0.978723 (-1175 100);
PAINT WHITE (-1175 100);
DISPLAY INVISIBLE (-1175 100);
FORCEPROP 0 LAST $SEC 1
J 0
(-975 50);
DISPLAY 0.680851 (-975 50);
PAINT MONO (-975 50);
DISPLAY INVISIBLE (-975 50);
FORCEPROP 0 LAST CDS_SEC 1
J 0
(-975 50);
DISPLAY 1.021277 (-975 50);
DISPLAY INVISIBLE (-975 50);
FORCEADD Q_RES..1
(-1125 -900);
FORCEPROP 1 LAST PART_NUMBER CS11002FB07
J 0
(-1250 -850);
DISPLAY 0.404255 (-1250 -850);
DISPLAY INVISIBLE (-1250 -850);
FORCEPROP 1 LAST MATERIAL CHIP
J 0
(-850 -900);
DISPLAY 0.510638 (-850 -900);
FORCEPROP 1 LAST WATTAGE 1/16W
J 2
(-975 -825);
DISPLAY 0.404255 (-975 -825);
FORCEPROP 1 LAST TOLERANCE 1%
J 0
(-925 -900);
DISPLAY 0.510638 (-925 -900);
FORCEPROP 1 LAST PACK_TYPE 0402LF
J 0
(-1250 -825);
DISPLAY 0.404255 (-1250 -825);
FORCEPROP 1 LAST VALUE 100
J 2
(-950 -900);
DISPLAY 0.510638 (-950 -900);
FORCEPROP 1 LAST LOCATION R158
J 0
(-1325 -900);
DISPLAY 0.638298 (-1325 -900);
FORCEPROP 1 LASTPIN (-1225 -900) $PN 1
J 0
(-1213 -888);
DISPLAY 0.787234 (-1213 -888);
PAINT MONO (-1213 -888);
FORCEPROP 1 LASTPIN (-1025 -900) $PN 2
J 0
(-1063 -888);
DISPLAY 0.787234 (-1063 -888);
PAINT MONO (-1063 -888);
FORCEPROP 2 LAST CDS_LIB pure_quanta
J 0
(-1125 -900);
DISPLAY INVISIBLE (-1125 -900);
FORCEPROP 1 LAST PATH I65
J 0
(-1175 -750);
DISPLAY 0.978723 (-1175 -750);
PAINT WHITE (-1175 -750);
DISPLAY INVISIBLE (-1175 -750);
FORCEPROP 0 LAST $SEC 1
J 0
(-975 -800);
DISPLAY 0.680851 (-975 -800);
PAINT MONO (-975 -800);
DISPLAY INVISIBLE (-975 -800);
FORCEPROP 0 LAST CDS_SEC 1
J 0
(-975 -800);
DISPLAY 1.021277 (-975 -800);
DISPLAY INVISIBLE (-975 -800);
FORCEADD Q_RES..1
(-1100 775);
FORCEPROP 1 LAST PART_NUMBER CS11002FB07
J 0
(-1200 825);
DISPLAY 0.404255 (-1200 825);
DISPLAY INVISIBLE (-1200 825);
FORCEPROP 1 LAST PACK_TYPE 0402LF
J 0
(-1250 850);
DISPLAY 0.404255 (-1250 850);
FORCEPROP 1 LAST MATERIAL CHIP
J 0
(-825 775);
DISPLAY 0.510638 (-825 775);
FORCEPROP 1 LAST TOLERANCE 1%
J 0
(-900 775);
DISPLAY 0.510638 (-900 775);
FORCEPROP 1 LAST WATTAGE 1/16W
J 2
(-950 850);
DISPLAY 0.404255 (-950 850);
FORCEPROP 1 LAST VALUE 100
J 2
(-925 775);
DISPLAY 0.510638 (-925 775);
FORCEPROP 1 LAST $LOCATION R4302
J 0
(-1300 775);
DISPLAY 0.638298 (-1300 775);
FORCEPROP 1 LASTPIN (-1200 775) $PN 1
J 0
(-1188 787);
DISPLAY 0.787234 (-1188 787);
PAINT MONO (-1188 787);
FORCEPROP 1 LASTPIN (-1000 775) $PN 2
J 0
(-1038 787);
DISPLAY 0.787234 (-1038 787);
PAINT MONO (-1038 787);
FORCEPROP 2 LAST CDS_LIB pure_quanta
J 0
(-1100 775);
DISPLAY INVISIBLE (-1100 775);
FORCEPROP 1 LAST PATH I66
J 0
(-1150 925);
DISPLAY 0.978723 (-1150 925);
PAINT WHITE (-1150 925);
DISPLAY INVISIBLE (-1150 925);
FORCEPROP 0 LAST CDS_LOCATION R4302
J 0
(-950 875);
DISPLAY 1.021277 (-950 875);
DISPLAY INVISIBLE (-950 875);
FORCEPROP 0 LAST $SEC 1
J 0
(-950 875);
DISPLAY 0.680851 (-950 875);
PAINT MONO (-950 875);
DISPLAY INVISIBLE (-950 875);
FORCEPROP 0 LAST CDS_SEC 1
J 0
(-950 875);
DISPLAY 1.021277 (-950 875);
DISPLAY INVISIBLE (-950 875);
FORCEADD OFFPAGE..2
(325 775);
FORCEPROP 2 LAST $XR0 45 
J 0
(514 775);
DISPLAY 0.638298 (514 775);
PAINT MONO (514 775);
FORCEPROP 2 LAST CDS_LIB standard
J 0
(325 775);
DISPLAY INVISIBLE (325 775);
FORCEPROP 1 LAST OFFPAGE TRUE
J 0
(650 650);
DISPLAY 0.872340 (650 650);
PAINT GREEN (650 650);
DISPLAY INVISIBLE (650 650);
FORCEPROP 1 LAST COMMENT_BODY TRUE
J 0
(280 680);
DISPLAY 0.872340 (280 680);
PAINT GREEN (280 680);
DISPLAY INVISIBLE (280 680);
FORCEPROP 2 LAST PATH I67
J 0
(525 825);
DISPLAY 1.021277 (525 825);
DISPLAY INVISIBLE (525 825);
FORCEADD Q_RES..1
(-1100 1600);
FORCEPROP 1 LAST PART_NUMBER CS11002FB07
J 0
(-1175 1650);
DISPLAY 0.404255 (-1175 1650);
DISPLAY INVISIBLE (-1175 1650);
FORCEPROP 1 LAST VALUE 100
J 2
(-925 1600);
DISPLAY 0.510638 (-925 1600);
FORCEPROP 1 LAST PACK_TYPE 0402LF
J 0
(-1250 1675);
DISPLAY 0.404255 (-1250 1675);
FORCEPROP 1 LAST TOLERANCE 1%
J 0
(-900 1600);
DISPLAY 0.510638 (-900 1600);
FORCEPROP 1 LAST WATTAGE 1/16W
J 2
(-950 1675);
DISPLAY 0.404255 (-950 1675);
FORCEPROP 1 LAST MATERIAL CHIP
J 0
(-825 1600);
DISPLAY 0.510638 (-825 1600);
FORCEPROP 1 LAST $LOCATION R4301
J 0
(-1275 1600);
DISPLAY 0.638298 (-1275 1600);
FORCEPROP 1 LASTPIN (-1200 1600) $PN 1
J 0
(-1188 1612);
DISPLAY 0.787234 (-1188 1612);
PAINT MONO (-1188 1612);
FORCEPROP 1 LASTPIN (-1000 1600) $PN 2
J 0
(-1038 1612);
DISPLAY 0.787234 (-1038 1612);
PAINT MONO (-1038 1612);
FORCEPROP 2 LAST CDS_LIB pure_quanta
J 0
(-1100 1600);
DISPLAY INVISIBLE (-1100 1600);
FORCEPROP 1 LAST PATH I68
J 0
(-1150 1750);
DISPLAY 0.978723 (-1150 1750);
PAINT WHITE (-1150 1750);
DISPLAY INVISIBLE (-1150 1750);
FORCEPROP 0 LAST CDS_LOCATION R4301
J 0
(-950 1700);
DISPLAY 1.021277 (-950 1700);
DISPLAY INVISIBLE (-950 1700);
FORCEPROP 0 LAST $SEC 1
J 0
(-950 1700);
DISPLAY 0.680851 (-950 1700);
PAINT MONO (-950 1700);
DISPLAY INVISIBLE (-950 1700);
FORCEPROP 0 LAST CDS_SEC 1
J 0
(-950 1700);
DISPLAY 1.021277 (-950 1700);
DISPLAY INVISIBLE (-950 1700);
FORCEADD OFFPAGE..2
(325 1600);
FORCEPROP 2 LAST $XR0 45 
J 0
(514 1600);
DISPLAY 0.638298 (514 1600);
PAINT MONO (514 1600);
FORCEPROP 2 LAST CDS_LIB standard
J 0
(325 1600);
DISPLAY INVISIBLE (325 1600);
FORCEPROP 1 LAST OFFPAGE TRUE
J 0
(650 1475);
DISPLAY 0.872340 (650 1475);
PAINT GREEN (650 1475);
DISPLAY INVISIBLE (650 1475);
FORCEPROP 1 LAST COMMENT_BODY TRUE
J 0
(280 1505);
DISPLAY 0.872340 (280 1505);
PAINT GREEN (280 1505);
DISPLAY INVISIBLE (280 1505);
FORCEPROP 2 LAST PATH I69
J 0
(525 1650);
DISPLAY 1.021277 (525 1650);
DISPLAY INVISIBLE (525 1650);
FORCEADD Q_RES..1
(-5300 775);
FORCEPROP 1 LAST PART_NUMBER CS00002JB13
J 0
(-5350 825);
DISPLAY 0.404255 (-5350 825);
DISPLAY INVISIBLE (-5350 825);
FORCEPROP 1 LAST VALUE 0
J 2
(-5150 775);
DISPLAY 0.510638 (-5150 775);
FORCEPROP 1 LAST TOLERANCE 5%
J 0
(-5125 775);
DISPLAY 0.510638 (-5125 775);
FORCEPROP 1 LAST MATERIAL CHIP
J 0
(-5350 850);
DISPLAY 0.404255 (-5350 850);
FORCEPROP 1 LAST WATTAGE 1/16W
J 2
(-5125 850);
DISPLAY 0.404255 (-5125 850);
FORCEPROP 1 LAST PACK_TYPE 0402LF
J 0
(-5050 775);
DISPLAY 0.510638 (-5050 775);
FORCEPROP 1 LAST $LOCATION R128
J 0
(-5500 775);
DISPLAY 0.638298 (-5500 775);
FORCEPROP 1 LASTPIN (-5400 775) $PN 1
J 0
(-5388 787);
DISPLAY 0.787234 (-5388 787);
FORCEPROP 1 LASTPIN (-5200 775) $PN 2
J 0
(-5238 787);
DISPLAY 0.787234 (-5238 787);
FORCEPROP 2 LAST CDS_LIB pure_quanta
J 0
(-5300 775);
PAINT MONO (-5300 775);
DISPLAY INVISIBLE (-5300 775);
FORCEPROP 1 LAST PATH I7
J 0
(-5350 925);
DISPLAY 0.978723 (-5350 925);
PAINT WHITE (-5350 925);
DISPLAY INVISIBLE (-5350 925);
FORCEPROP 2 LAST CDS_LOCATION R128
J 0
(-5350 975);
DISPLAY 1.021277 (-5350 975);
DISPLAY INVISIBLE (-5350 975);
FORCEPROP 2 LAST $SEC 1
J 0
(-5350 975);
DISPLAY 0.680851 (-5350 975);
PAINT MONO (-5350 975);
DISPLAY INVISIBLE (-5350 975);
FORCEPROP 2 LAST CDS_SEC 1
J 0
(-5350 975);
DISPLAY 1.021277 (-5350 975);
DISPLAY INVISIBLE (-5350 975);
FORCEADD Q_RES..1
(-1100 2450);
FORCEPROP 1 LAST PART_NUMBER CS11002FB07
J 0
(-1175 2500);
DISPLAY 0.404255 (-1175 2500);
DISPLAY INVISIBLE (-1175 2500);
FORCEPROP 1 LAST VALUE 100
J 2
(-925 2450);
DISPLAY 0.510638 (-925 2450);
FORCEPROP 1 LAST PACK_TYPE 0402LF
J 0
(-1250 2525);
DISPLAY 0.404255 (-1250 2525);
FORCEPROP 1 LAST WATTAGE 1/16W
J 2
(-950 2525);
DISPLAY 0.404255 (-950 2525);
FORCEPROP 1 LAST TOLERANCE 1%
J 0
(-900 2450);
DISPLAY 0.510638 (-900 2450);
FORCEPROP 1 LAST MATERIAL CHIP
J 0
(-825 2450);
DISPLAY 0.510638 (-825 2450);
FORCEPROP 1 LAST $LOCATION R4300
J 0
(-1275 2450);
DISPLAY 0.638298 (-1275 2450);
FORCEPROP 1 LASTPIN (-1200 2450) $PN 1
J 0
(-1188 2462);
DISPLAY 0.787234 (-1188 2462);
PAINT MONO (-1188 2462);
FORCEPROP 1 LASTPIN (-1000 2450) $PN 2
J 0
(-1038 2462);
DISPLAY 0.787234 (-1038 2462);
PAINT MONO (-1038 2462);
FORCEPROP 2 LAST CDS_LIB pure_quanta
J 0
(-1100 2450);
DISPLAY INVISIBLE (-1100 2450);
FORCEPROP 1 LAST PATH I70
J 0
(-1150 2600);
DISPLAY 0.978723 (-1150 2600);
PAINT WHITE (-1150 2600);
DISPLAY INVISIBLE (-1150 2600);
FORCEPROP 0 LAST CDS_LOCATION R4300
J 0
(-950 2550);
DISPLAY 1.021277 (-950 2550);
DISPLAY INVISIBLE (-950 2550);
FORCEPROP 0 LAST $SEC 1
J 0
(-950 2550);
DISPLAY 0.680851 (-950 2550);
PAINT MONO (-950 2550);
DISPLAY INVISIBLE (-950 2550);
FORCEPROP 0 LAST CDS_SEC 1
J 0
(-950 2550);
DISPLAY 1.021277 (-950 2550);
DISPLAY INVISIBLE (-950 2550);
FORCEADD OFFPAGE..2
(325 2450);
FORCEPROP 2 LAST $XR0 45 
J 0
(514 2450);
DISPLAY 0.638298 (514 2450);
PAINT MONO (514 2450);
FORCEPROP 2 LAST CDS_LIB standard
J 0
(325 2450);
DISPLAY INVISIBLE (325 2450);
FORCEPROP 1 LAST OFFPAGE TRUE
J 0
(650 2325);
DISPLAY 0.872340 (650 2325);
PAINT GREEN (650 2325);
DISPLAY INVISIBLE (650 2325);
FORCEPROP 1 LAST COMMENT_BODY TRUE
J 0
(280 2355);
DISPLAY 0.872340 (280 2355);
PAINT GREEN (280 2355);
DISPLAY INVISIBLE (280 2355);
FORCEPROP 2 LAST PATH I71
J 0
(525 2500);
DISPLAY 1.021277 (525 2500);
DISPLAY INVISIBLE (525 2500);
FORCEADD Q_RES..1
(-1100 3300);
FORCEPROP 1 LAST PART_NUMBER CS11002FB07
J 0
(-1150 3350);
DISPLAY 0.404255 (-1150 3350);
DISPLAY INVISIBLE (-1150 3350);
FORCEPROP 1 LAST VALUE 100
J 2
(-925 3300);
DISPLAY 0.510638 (-925 3300);
FORCEPROP 1 LAST PACK_TYPE 0402LF
J 0
(-1250 3375);
DISPLAY 0.404255 (-1250 3375);
FORCEPROP 1 LAST MATERIAL CHIP
J 0
(-825 3300);
DISPLAY 0.510638 (-825 3300);
FORCEPROP 1 LAST WATTAGE 1/16W
J 2
(-950 3375);
DISPLAY 0.404255 (-950 3375);
FORCEPROP 1 LAST TOLERANCE 1%
J 0
(-900 3300);
DISPLAY 0.510638 (-900 3300);
FORCEPROP 1 LAST $LOCATION R4299
J 0
(-1300 3300);
DISPLAY 0.638298 (-1300 3300);
FORCEPROP 1 LASTPIN (-1200 3300) $PN 1
J 0
(-1188 3312);
DISPLAY 0.787234 (-1188 3312);
PAINT MONO (-1188 3312);
FORCEPROP 1 LASTPIN (-1000 3300) $PN 2
J 0
(-1038 3312);
DISPLAY 0.787234 (-1038 3312);
PAINT MONO (-1038 3312);
FORCEPROP 2 LAST CDS_LIB pure_quanta
J 0
(-1100 3300);
DISPLAY INVISIBLE (-1100 3300);
FORCEPROP 1 LAST PATH I72
J 0
(-1150 3450);
DISPLAY 0.978723 (-1150 3450);
PAINT WHITE (-1150 3450);
DISPLAY INVISIBLE (-1150 3450);
FORCEPROP 0 LAST CDS_LOCATION R4299
J 0
(-950 3400);
DISPLAY 1.021277 (-950 3400);
DISPLAY INVISIBLE (-950 3400);
FORCEPROP 0 LAST $SEC 1
J 0
(-950 3400);
DISPLAY 0.680851 (-950 3400);
PAINT MONO (-950 3400);
DISPLAY INVISIBLE (-950 3400);
FORCEPROP 0 LAST CDS_SEC 1
J 0
(-950 3400);
DISPLAY 1.021277 (-950 3400);
DISPLAY INVISIBLE (-950 3400);
FORCEADD OFFPAGE..2
(375 3300);
FORCEPROP 2 LAST $XR0 45 
J 0
(564 3300);
DISPLAY 0.638298 (564 3300);
PAINT MONO (564 3300);
FORCEPROP 2 LAST CDS_LIB standard
J 0
(375 3300);
DISPLAY INVISIBLE (375 3300);
FORCEPROP 1 LAST OFFPAGE TRUE
J 0
(700 3175);
DISPLAY 0.872340 (700 3175);
PAINT GREEN (700 3175);
DISPLAY INVISIBLE (700 3175);
FORCEPROP 1 LAST COMMENT_BODY TRUE
J 0
(330 3205);
DISPLAY 0.872340 (330 3205);
PAINT GREEN (330 3205);
DISPLAY INVISIBLE (330 3205);
FORCEPROP 2 LAST PATH I73
J 0
(575 3350);
DISPLAY 1.021277 (575 3350);
DISPLAY INVISIBLE (575 3350);
FORCEADD OFFPAGE..1
(-6750 1600);
FORCEPROP 2 LAST $XR1 219 
J 0
(-7122 1600);
DISPLAY 0.638298 (-7122 1600);
PAINT MONO (-7122 1600);
FORCEPROP 2 LAST $XR0 216 
J 0
(-7002 1600);
DISPLAY 0.638298 (-7002 1600);
PAINT MONO (-7002 1600);
FORCEPROP 2 LAST CDS_LIB standard
J 0
(-6750 1600);
PAINT MONO (-6750 1600);
DISPLAY INVISIBLE (-6750 1600);
FORCEPROP 1 LAST OFFPAGE TRUE
J 0
(-6425 1475);
DISPLAY 0.872340 (-6425 1475);
PAINT GREEN (-6425 1475);
DISPLAY INVISIBLE (-6425 1475);
FORCEPROP 1 LAST COMMENT_BODY TRUE
J 0
(-6625 1500);
DISPLAY 0.872340 (-6625 1500);
PAINT GREEN (-6625 1500);
DISPLAY INVISIBLE (-6625 1500);
FORCEPROP 2 LAST PATH I8
J 0
(-6700 1675);
DISPLAY 1.021277 (-6700 1675);
DISPLAY INVISIBLE (-6700 1675);
FORCEADD OFFPAGE..1
(-6750 2450);
FORCEPROP 2 LAST $XR1 219 
J 0
(-7122 2450);
DISPLAY 0.638298 (-7122 2450);
PAINT MONO (-7122 2450);
FORCEPROP 2 LAST $XR0 216 
J 0
(-7002 2450);
DISPLAY 0.638298 (-7002 2450);
PAINT MONO (-7002 2450);
FORCEPROP 2 LAST CDS_LIB standard
J 0
(-6750 2450);
PAINT MONO (-6750 2450);
DISPLAY INVISIBLE (-6750 2450);
FORCEPROP 1 LAST OFFPAGE TRUE
J 0
(-6425 2325);
DISPLAY 0.872340 (-6425 2325);
PAINT GREEN (-6425 2325);
DISPLAY INVISIBLE (-6425 2325);
FORCEPROP 1 LAST COMMENT_BODY TRUE
J 0
(-6625 2350);
DISPLAY 0.872340 (-6625 2350);
PAINT GREEN (-6625 2350);
DISPLAY INVISIBLE (-6625 2350);
FORCEPROP 2 LAST PATH I9
J 0
(-6700 2525);
DISPLAY 1.021277 (-6700 2525);
DISPLAY INVISIBLE (-6700 2525);
FORCEADD QUANTA_TITLE_BLOCK_C..1
(1450 -2300);
FORCEPROP 0 LAST CDS_CON_LAST_MODIFIED Fri Aug 25 14:01:45 2023
J 0
(-435 -2285);
PAINT MONO (-435 -2285);
DISPLAY INVISIBLE (-435 -2285);
FORCEPROP 1 LAST CUSTOM_TXT_CDS <CON_LAST_MODIFIED>
J 0
(-435 -2285);
DISPLAY 0.978723 (-435 -2285);
FORCEPROP 2 LAST CUSTOM_TXT_CDS <XR_PAGE_TITLE>
J 0
(-6440 2950);
DISPLAY 0.638298 (-6440 2950);
PAINT PINK (-6440 2950);
DISPLAY INVISIBLE (-6440 2950);
FORCEPROP 2 LAST CUSTOM_TXT_CDS <NAME_1>
J 0
(-1725 -2125);
FORCEPROP 2 LAST CUSTOM_TXT_CDS <Q_REV>
J 0
(1266 -2197);
DISPLAY 1.212766 (1266 -2197);
FORCEPROP 2 LAST CUSTOM_TXT_CDS <CON_PAGE_NUM> OF <CON_TOTAL_PAGES>
J 0
(1004 -2282);
DISPLAY 0.978723 (1004 -2282);
FORCEPROP 2 LAST CUSTOM_TXT_CDS <Q_NUMBER>
J 0
(47 -2197);
DISPLAY 1.212766 (47 -2197);
FORCEPROP 2 LAST CUSTOM_TXT_CDS <Q_PROJ>
J 0
(-932 -2198);
DISPLAY 1.212766 (-932 -2198);
FORCEPROP 2 LAST CUSTOM_TXT_CDS <NAME_2>
J 0
(-1725 -2250);
FORCEPROP 1 LAST Q_TITLE SPR CPU0 & 1 - CPU1 PWRGDS/RESET
J 0
(-7816 -2299);
DISPLAY 2.446809 (-7816 -2299);
PAINT GREEN (-7816 -2299);
FORCEPROP 1 LAST Q_DEPT 
J 1
(-2313 -2251);
DISPLAY 1.957447 (-2313 -2251);
PAINT GREEN (-2313 -2251);
FORCEPROP 2 LAST CDS_XR_PAGE_TITLE CR-125 : @S9S_MB_2U_LIB.S9S_MB_2U(SCH_1):PAGE125
J 0
(-6440 2950);
DISPLAY 0.638298 (-6440 2950);
PAINT PINK (-6440 2950);
DISPLAY INVISIBLE (-6440 2950);
FORCEPROP 2 LAST CDS_LIB pure_quanta
J 0
(1450 -2300);
PAINT MONO (1450 -2300);
DISPLAY INVISIBLE (1450 -2300);
FORCEPROP 1 LAST CDS_LMAN_SYM_OUTLINE -9475,6775,100,-125
J 0
(1450 -2300);
DISPLAY 0.468085 (1450 -2300);
PAINT GREEN (1450 -2300);
DISPLAY INVISIBLE (1450 -2300);
FORCEPROP 1 LAST COMMENT_BODY TRUE
J 0
(1462 -2313);
DISPLAY 0.978723 (1462 -2313);
PAINT GREEN (1462 -2313);
DISPLAY INVISIBLE (1462 -2313);
FORCEPROP 2 LAST PAGE_BORDER TRUE
J 0
(-6440 2950);
DISPLAY 0.638298 (-6440 2950);
PAINT PINK (-6440 2950);
DISPLAY INVISIBLE (-6440 2950);
WIRE 16 -1 (-525 175)(-525 125);
WIRE 16 -1 (-500 1000)(-500 950);
WIRE 16 -1 (-500 2675)(-500 2625);
WIRE 16 -1 (-500 3500)(-500 3450);
WIRE 16 -1 (-525 -675)(-525 -725);
WIRE 16 -1 (-500 1825)(-500 1775);
WIRE 16 -1 (-175 -50)(-1025 -50);
FORCEPROP 2 LAST SIG_NAME PWRGD_CPU1_LVC1
J 0
(-635 -40);
DISPLAY 0.553191 (-635 -40);
PAINT WHITE (-635 -40);
WIRE 16 -1 (-1025 125)(-525 125);
WIRE 16 2175 (-1325 -100)(-750 -100);
WIRE 16 2175 (-750 50)(-750 -100);
WIRE 16 2175 (-1325 50)(-1325 -100);
WIRE 16 2175 (-1325 50)(-750 50);
WIRE 16 -1 (275 775)(-1000 775);
FORCEPROP 2 LAST SIG_NAME PWRGD_DRAMPWRGD_CPU1_GH_LVC1_R
J 0
(-635 785);
DISPLAY 0.553191 (-635 785);
PAINT WHITE (-635 785);
WIRE 16 -1 (-1000 950)(-500 950);
WIRE 16 2175 (-1300 900)(-725 900);
WIRE 16 2175 (-725 900)(-725 750);
WIRE 16 2175 (-1300 900)(-1300 750);
WIRE 16 2175 (-1300 750)(-725 750);
WIRE 16 -1 (-1450 1775)(-1200 1775);
WIRE 16 -1 (-1450 1600)(-5200 1600);
WIRE 16 -1 (-1450 1600)(-1450 1775);
WIRE 16 -1 (-1450 1600)(-1200 1600);
FORCEPROP 2 LAST SIG_NAME PWRGD_DRAMPWRGD_CPU1_EF_LVC1_R2
J 0
(-2285 1610);
DISPLAY 0.553191 (-2285 1610);
PAINT WHITE (-2285 1610);
WIRE 16 2175 (-1300 1725)(-725 1725);
WIRE 16 2175 (-725 1725)(-725 1575);
WIRE 16 2175 (-1300 1725)(-1300 1575);
WIRE 16 2175 (-1300 1575)(-725 1575);
WIRE 16 -1 (-1000 1775)(-500 1775);
WIRE 16 2175 (-1300 2550)(-725 2550);
WIRE 16 2175 (-725 2550)(-725 2400);
WIRE 16 2175 (-1300 2550)(-1300 2400);
WIRE 16 2175 (-1300 2400)(-725 2400);
WIRE 16 -1 (275 2450)(-1000 2450);
FORCEPROP 2 LAST SIG_NAME PWRGD_DRAMPWRGD_CPU1_CD_LVC1_R
J 0
(-635 2460);
DISPLAY 0.553191 (-635 2460);
PAINT WHITE (-635 2460);
WIRE 16 -1 (-1000 2625)(-500 2625);
WIRE 16 2175 (-1300 3425)(-725 3425);
WIRE 16 2175 (-725 3425)(-725 3275);
WIRE 16 2175 (-1300 3425)(-1300 3275);
WIRE 16 2175 (-1300 3275)(-725 3275);
WIRE 16 -1 (-1025 -725)(-525 -725);
WIRE 16 -1 (-1000 3450)(-500 3450);
WIRE 16 -1 (-1450 775)(-5200 775);
WIRE 16 -1 (-1450 775)(-1200 775);
WIRE 16 -1 (-1450 775)(-1450 950);
FORCEPROP 2 LAST SIG_NAME PWRGD_DRAMPWRGD_CPU1_GH_LVC1_R2
J 0
(-2410 785);
DISPLAY 0.553191 (-2410 785);
PAINT WHITE (-2410 785);
WIRE 16 -1 (-1450 950)(-1200 950);
WIRE 16 -1 (-1000 1600)(275 1600);
FORCEPROP 2 LAST SIG_NAME PWRGD_DRAMPWRGD_CPU1_EF_LVC1_R
J 0
(-610 1610);
DISPLAY 0.553191 (-610 1610);
PAINT WHITE (-610 1610);
WIRE 16 -1 (-1000 3300)(325 3300);
FORCEPROP 2 LAST SIG_NAME PWRGD_DRAMPWRGD_CPU1_AB_LVC1_R
J 0
(-485 3310);
DISPLAY 0.553191 (-485 3310);
PAINT WHITE (-485 3310);
WIRE 16 -1 (-1450 3275)(-5200 3275);
WIRE 16 -1 (-1450 3300)(-1450 3275);
WIRE 16 -1 (-1450 3300)(-1200 3300);
WIRE 16 -1 (-1450 3300)(-1450 3450);
FORCEPROP 2 LAST SIG_NAME PWRGD_DRAMPWRGD_CPU1_AB_LVC1_R2
J 0
(-2285 3310);
DISPLAY 0.553191 (-2285 3310);
PAINT WHITE (-2285 3310);
WIRE 16 -1 (-1450 3450)(-1200 3450);
WIRE 16 -1 (-5200 2450)(-1450 2450);
WIRE 16 -1 (-1200 2450)(-1450 2450);
FORCEPROP 2 LAST SIG_NAME PWRGD_DRAMPWRGD_CPU1_CD_LVC1_R2
J 0
(-2285 2460);
DISPLAY 0.553191 (-2285 2460);
PAINT WHITE (-2285 2460);
WIRE 16 -1 (-1450 2450)(-1450 2625);
WIRE 16 -1 (-1450 2625)(-1200 2625);
WIRE 16 -1 (-1450 -50)(-5200 -50);
FORCEPROP 2 LAST SIG_NAME PWRGD_CPU1_BUF_R
J 0
(-2085 -40);
DISPLAY 0.553191 (-2085 -40);
PAINT WHITE (-2085 -40);
WIRE 16 -1 (-1225 -50)(-1450 -50);
WIRE 16 -1 (-1450 125)(-1450 -50);
WIRE 16 -1 (-1450 125)(-1225 125);
WIRE 16 -1 (-6700 1600)(-5400 1600);
FORCEPROP 2 LAST SIG_NAME PWRGD_DRAMPWRGD_CPU1_EF_R_LVC1
J 0
(-6585 1610);
DISPLAY 0.553191 (-6585 1610);
PAINT WHITE (-6585 1610);
WIRE 16 2175 (-1325 -925)(-750 -925);
WIRE 16 2175 (-750 -775)(-750 -925);
WIRE 16 2175 (-1325 -775)(-1325 -925);
WIRE 16 2175 (-1325 -775)(-750 -775);
WIRE 16 -1 (-175 -900)(-1025 -900);
FORCEPROP 2 LAST SIG_NAME RST_CPU1_LVC1_N
J 0
(-735 -890);
DISPLAY 0.553191 (-735 -890);
PAINT WHITE (-735 -890);
WIRE 16 -1 (-5200 -900)(-1450 -900);
FORCEPROP 2 LAST SIG_NAME RST_CPU1_BUF_R_N
J 0
(-2085 -890);
DISPLAY 0.553191 (-2085 -890);
PAINT WHITE (-2085 -890);
WIRE 16 -1 (-1225 -900)(-1450 -900);
WIRE 16 -1 (-1450 -725)(-1450 -900);
WIRE 16 -1 (-1450 -725)(-1225 -725);
WIRE 16 -1 (-6700 -50)(-5400 -50);
FORCEPROP 2 LAST SIG_NAME PWRGD_CPU1_LVC1_R
J 0
(-6585 -40);
DISPLAY 0.553191 (-6585 -40);
PAINT WHITE (-6585 -40);
WIRE 16 -1 (-6700 2450)(-5400 2450);
FORCEPROP 2 LAST SIG_NAME PWRGD_DRAMPWRGD_CPU1_CD_R_LVC1
J 0
(-6585 2460);
DISPLAY 0.553191 (-6585 2460);
PAINT WHITE (-6585 2460);
WIRE 16 -1 (-6700 -900)(-5400 -900);
FORCEPROP 2 LAST SIG_NAME RST_CPU1_LVC1_R_N
J 0
(-6585 -890);
DISPLAY 0.553191 (-6585 -890);
PAINT WHITE (-6585 -890);
WIRE 16 -1 (-6700 775)(-5400 775);
FORCEPROP 2 LAST SIG_NAME PWRGD_DRAMPWRGD_CPU1_GH_R_LVC1
J 0
(-6585 785);
DISPLAY 0.553191 (-6585 785);
PAINT WHITE (-6585 785);
WIRE 16 -1 (-5400 3275)(-6700 3275);
FORCEPROP 2 LAST SIG_NAME PWRGD_DRAMPWRGD_CPU1_AB_R_LVC1
J 0
(-6585 3285);
DISPLAY 0.553191 (-6585 3285);
PAINT WHITE (-6585 3285);
DOT 1 (-1450 3300);
DOT 1 (-1450 2450);
DOT 1 (-1450 1600);
DOT 1 (-1450 775);
DOT 1 (-1450 -50);
DOT 1 (-1450 -900);
FORCENOTE
20210907 MODIFY FOR GT
(-7250 3875) 0;
DISPLAY LEFT (-7250 3875);
DISPLAY 2.510638 (-7250 3875);
PAINT PINK (-7250 3875);
FORCENOTE
CPLD
(-6900 2550) 0;
DISPLAY LEFT (-6900 2550);
DISPLAY 1.276596 (-6900 2550);
PAINT SKYBLUE (-6900 2550);
FORCENOTE
CPLD
(-6900 -800) 0;
DISPLAY LEFT (-6900 -800);
DISPLAY 1.276596 (-6900 -800);
PAINT SKYBLUE (-6900 -800);
FORCENOTE
CPLD
(-6900 50) 0;
DISPLAY LEFT (-6900 50);
DISPLAY 1.276596 (-6900 50);
PAINT SKYBLUE (-6900 50);
FORCENOTE
CPLD
(-6900 875) 0;
DISPLAY LEFT (-6900 875);
DISPLAY 1.276596 (-6900 875);
PAINT SKYBLUE (-6900 875);
FORCENOTE
CPLD
(-6900 1700) 0;
DISPLAY LEFT (-6900 1700);
DISPLAY 1.276596 (-6900 1700);
PAINT SKYBLUE (-6900 1700);
FORCENOTE
CPLD
(-6900 3375) 0;
DISPLAY LEFT (-6900 3375);
DISPLAY 1.276596 (-6900 3375);
PAINT SKYBLUE (-6900 3375);
FORCENOTE
20211129 R158 CHANGE TO 100 OHM
(-1700 -1050) 0;
DISPLAY LEFT (-1700 -1050);
DISPLAY 1.063830 (-1700 -1050);
PAINT WHITE (-1700 -1050);
FORCENOTE
20211129 R156 CHANGE TO 100 OHM
(-1700 -225) 0;
DISPLAY LEFT (-1700 -225);
DISPLAY 1.063830 (-1700 -225);
PAINT WHITE (-1700 -225);
FORCENOTE
20211206 ADD R4299,R4300,R4301,R4302
(-1500 675) 0;
DISPLAY LEFT (-1500 675);
DISPLAY 1.063830 (-1500 675);
PAINT WHITE (-1500 675);
QUIT
